(kicad_pcb
	(version 20260206)
	(generator "pcbnew")
	(generator_version "10.0")
	(general
		(thickness 1.6)
		(legacy_teardrops no)
	)
	(paper "A4")
	(title_block
		(title "01162023_DA0F0TEBIF0_F0T_Expander_BD_F_brd_V02_OCP.brd")
		(comment 1 "Grand Teton / footprints 7696-7703 of 9728")
	)
	(layers
		(0 "F.Cu" signal "TOP")
		(4 "In1.Cu" signal "GND")
		(6 "In2.Cu" signal "VCC")
		(8 "In3.Cu" signal "VCC1")
		(10 "In4.Cu" signal "GND1")
		(12 "In5.Cu" signal "IN1")
		(14 "In6.Cu" signal "GND2")
		(16 "In7.Cu" signal "IN2")
		(18 "In8.Cu" signal "GND3")
		(20 "In9.Cu" signal "IN3")
		(22 "In10.Cu" signal "GND4")
		(24 "In11.Cu" signal "IN4")
		(26 "In12.Cu" signal "GND5")
		(28 "In13.Cu" signal "IN5")
		(30 "In14.Cu" signal "GND6")
		(32 "In15.Cu" signal "IN6")
		(34 "In16.Cu" signal "GND7")
		(2 "B.Cu" signal "BOTTOM")
		(9 "F.Adhes" user "F.Adhesive")
		(11 "B.Adhes" user "B.Adhesive")
		(13 "F.Paste" user "Package Geometry/Pastemask Top")
		(15 "B.Paste" user "Package Geometry/Pastemask Bottom")
		(5 "F.SilkS" user "Ref Des/Silkscreen Top")
		(7 "B.SilkS" user "Ref Des/Silkscreen Bottom")
		(1 "F.Mask" user "Board Geometry/Soldermask Top")
		(3 "B.Mask" user "Board Geometry/Soldermask Bottom")
		(17 "Dwgs.User" user "User.Drawings")
		(19 "Cmts.User" user "User.Comments")
		(21 "Eco1.User" user "User.Eco1")
		(23 "Eco2.User" user "User.Eco2")
		(25 "Edge.Cuts" user "Board Geometry/Outline")
		(27 "Margin" user)
		(31 "F.CrtYd" user "Package Geometry/Place Bound Top")
		(29 "B.CrtYd" user "Package Geometry/Place Bound Bottom")
		(35 "F.Fab" user "Ref Des/Assembly Top")
		(33 "B.Fab" user "Ref Des/Assembly Bottom")
	)
	(footprint ""
		(layer "B.Cu")
		(at 243.3193 -205.19517 180)
		(property "Reference" "C2016"
			(at 0 0 0)
			(layer "B.SilkS")
			(hide yes)
			(effects
				(font
					(size 1.27 1.27)
				)
				(justify mirror)
			)
		)
		(property "Value" ""
			(at 0 0 0)
			(layer "B.Fab")
			(effects
				(font
					(size 1.27 1.27)
				)
				(justify mirror)
			)
		)
		(duplicate_pad_numbers_are_jumpers no)
		(fp_line
			(start 1.2954 0.5842)
			(end 1.2954 -0.5842)
			(stroke
				(width 0.1524)
				(type default)
			)
			(layer "B.SilkS")
		)
		(fp_line
			(start 1.2954 -0.5842)
			(end -1.2954 -0.5842)
			(stroke
				(width 0.1524)
				(type default)
			)
			(layer "B.SilkS")
		)
		(fp_line
			(start -1.2954 0.5842)
			(end 1.2954 0.5842)
			(stroke
				(width 0.1524)
				(type default)
			)
			(layer "B.SilkS")
		)
		(fp_line
			(start -1.2954 -0.5842)
			(end -1.2954 0.5842)
			(stroke
				(width 0.1524)
				(type default)
			)
			(layer "B.SilkS")
		)
		(fp_line
			(start 1.1938 0.4064)
			(end 1.1938 -0.4064)
			(stroke
				(width 0.1)
				(type default)
			)
			(layer "B.Fab")
		)
		(fp_line
			(start 1.1938 -0.4064)
			(end 0.8636 -0.4064)
			(stroke
				(width 0.1)
				(type default)
			)
			(layer "B.Fab")
		)
		(fp_line
			(start 0.8636 0.4572)
			(end 0.8636 0.4064)
			(stroke
				(width 0.1)
				(type default)
			)
			(layer "B.Fab")
		)
		(fp_line
			(start 0.8636 0.4064)
			(end 1.1938 0.4064)
			(stroke
				(width 0.1)
				(type default)
			)
			(layer "B.Fab")
		)
		(fp_line
			(start 0.8636 -0.4064)
			(end 0.8636 -0.4572)
			(stroke
				(width 0.1)
				(type default)
			)
			(layer "B.Fab")
		)
		(fp_line
			(start 0.8636 -0.4572)
			(end -0.8636 -0.4572)
			(stroke
				(width 0.1)
				(type default)
			)
			(layer "B.Fab")
		)
		(fp_line
			(start -0.8636 0.4572)
			(end 0.8636 0.4572)
			(stroke
				(width 0.1)
				(type default)
			)
			(layer "B.Fab")
		)
		(fp_line
			(start -0.8636 0.4064)
			(end -0.8636 0.4572)
			(stroke
				(width 0.1)
				(type default)
			)
			(layer "B.Fab")
		)
		(fp_line
			(start -0.8636 -0.4064)
			(end -1.1938 -0.4064)
			(stroke
				(width 0.1)
				(type default)
			)
			(layer "B.Fab")
		)
		(fp_line
			(start -0.8636 -0.4572)
			(end -0.8636 -0.4064)
			(stroke
				(width 0.1)
				(type default)
			)
			(layer "B.Fab")
		)
		(fp_line
			(start -1.1938 0.4064)
			(end -0.8636 0.4064)
			(stroke
				(width 0.1)
				(type default)
			)
			(layer "B.Fab")
		)
		(fp_line
			(start -1.1938 -0.4064)
			(end -1.1938 0.4064)
			(stroke
				(width 0.1)
				(type default)
			)
			(layer "B.Fab")
		)
		(pad "1" smd rect
			(at 0.7366 0 90)
			(size 0.7112 0.8128)
			(layers "B.Cu" "B.Mask" "B.Paste")
			(net "P1V2_AUX")
		)
		(pad "2" smd rect
			(at -0.7366 0 90)
			(size 0.7112 0.8128)
			(layers "B.Cu" "B.Mask" "B.Paste")
			(net "GND")
		)
	)
	(footprint ""
		(layer "B.Cu")
		(at 351.645982 -143.51 180)
		(property "Reference" "R4792"
			(at 0 0 0)
			(layer "B.SilkS")
			(hide yes)
			(effects
				(font
					(size 1.27 1.27)
				)
				(justify mirror)
			)
		)
		(property "Value" ""
			(at 0 0 0)
			(layer "B.Fab")
			(effects
				(font
					(size 1.27 1.27)
				)
				(justify mirror)
			)
		)
		(duplicate_pad_numbers_are_jumpers no)
		(fp_line
			(start 0.7874 0.4064)
			(end 0.7874 -0.4064)
			(stroke
				(width 0.1524)
				(type default)
			)
			(layer "B.SilkS")
		)
		(fp_line
			(start 0.7874 -0.4064)
			(end -0.7874 -0.4064)
			(stroke
				(width 0.1524)
				(type default)
			)
			(layer "B.SilkS")
		)
		(fp_line
			(start -0.7874 0.4064)
			(end 0.7874 0.4064)
			(stroke
				(width 0.1524)
				(type default)
			)
			(layer "B.SilkS")
		)
		(fp_line
			(start -0.7874 -0.4064)
			(end -0.7874 0.4064)
			(stroke
				(width 0.1524)
				(type default)
			)
			(layer "B.SilkS")
		)
		(fp_line
			(start 0.67945 0.3048)
			(end 0.67945 -0.305054)
			(stroke
				(width 0.1)
				(type default)
			)
			(layer "B.Fab")
		)
		(fp_line
			(start 0.67945 -0.305054)
			(end 0.12065 -0.305054)
			(stroke
				(width 0.1)
				(type default)
			)
			(layer "B.Fab")
		)
		(fp_line
			(start 0.12065 0.3048)
			(end 0.67945 0.3048)
			(stroke
				(width 0.1)
				(type default)
			)
			(layer "B.Fab")
		)
		(fp_line
			(start 0.12065 0.2794)
			(end 0.12065 0.3048)
			(stroke
				(width 0.1)
				(type default)
			)
			(layer "B.Fab")
		)
		(fp_line
			(start 0.12065 -0.2794)
			(end -0.12065 -0.2794)
			(stroke
				(width 0.1)
				(type default)
			)
			(layer "B.Fab")
		)
		(fp_line
			(start 0.12065 -0.305054)
			(end 0.12065 -0.2794)
			(stroke
				(width 0.1)
				(type default)
			)
			(layer "B.Fab")
		)
		(fp_line
			(start -0.120396 0.3048)
			(end -0.120396 0.2794)
			(stroke
				(width 0.1)
				(type default)
			)
			(layer "B.Fab")
		)
		(fp_line
			(start -0.120396 0.2794)
			(end 0.12065 0.2794)
			(stroke
				(width 0.1)
				(type default)
			)
			(layer "B.Fab")
		)
		(fp_line
			(start -0.12065 -0.2794)
			(end -0.12065 -0.3048)
			(stroke
				(width 0.1)
				(type default)
			)
			(layer "B.Fab")
		)
		(fp_line
			(start -0.12065 -0.3048)
			(end -0.67945 -0.3048)
			(stroke
				(width 0.1)
				(type default)
			)
			(layer "B.Fab")
		)
		(fp_line
			(start -0.67945 0.3048)
			(end -0.120396 0.3048)
			(stroke
				(width 0.1)
				(type default)
			)
			(layer "B.Fab")
		)
		(fp_line
			(start -0.67945 -0.3048)
			(end -0.67945 0.3048)
			(stroke
				(width 0.1)
				(type default)
			)
			(layer "B.Fab")
		)
		(pad "1" smd circle
			(at 0.40005 0)
			(size 0 0)
			(layers "B.Cu" "B.Mask" "B.Paste")
			(net "P3V3_AUX")
		)
		(pad "2" smd circle
			(at -0.40005 0)
			(size 0 0)
			(layers "B.Cu" "B.Mask" "B.Paste")
			(net "NIC7_PEX_PWR_EN_R")
		)
	)
	(footprint ""
		(layer "B.Cu")
		(at 129.780284 -284.796738 -90)
		(property "Reference" "PC114"
			(at 0 0 90)
			(layer "B.SilkS")
			(hide yes)
			(effects
				(font
					(size 1.27 1.27)
				)
				(justify mirror)
			)
		)
		(property "Value" ""
			(at 0 0 90)
			(layer "B.Fab")
			(effects
				(font
					(size 1.27 1.27)
				)
				(justify mirror)
			)
		)
		(duplicate_pad_numbers_are_jumpers no)
		(fp_line
			(start -1.524 0.762)
			(end 1.524 0.762)
			(stroke
				(width 0.1524)
				(type default)
			)
			(layer "B.SilkS")
		)
		(fp_line
			(start 1.524 0.762)
			(end 1.524 -0.762)
			(stroke
				(width 0.1524)
				(type default)
			)
			(layer "B.SilkS")
		)
		(fp_line
			(start -1.524 -0.762)
			(end -1.524 0.762)
			(stroke
				(width 0.1524)
				(type default)
			)
			(layer "B.SilkS")
		)
		(fp_line
			(start 1.524 -0.762)
			(end -1.524 -0.762)
			(stroke
				(width 0.1524)
				(type default)
			)
			(layer "B.SilkS")
		)
		(fp_line
			(start -1.1049 0.724916)
			(end -1.1049 -0.724916)
			(stroke
				(width 0.1)
				(type default)
			)
			(layer "B.Fab")
		)
		(fp_line
			(start 1.1049 0.724916)
			(end -1.1049 0.724916)
			(stroke
				(width 0.1)
				(type default)
			)
			(layer "B.Fab")
		)
		(fp_line
			(start -1.1049 -0.724916)
			(end 1.1049 -0.724916)
			(stroke
				(width 0.1)
				(type default)
			)
			(layer "B.Fab")
		)
		(fp_line
			(start 1.1049 -0.724916)
			(end 1.1049 0.724916)
			(stroke
				(width 0.1)
				(type default)
			)
			(layer "B.Fab")
		)
		(pad "1" smd rect
			(at 0.889 0 270)
			(size 1.016 1.27)
			(layers "B.Cu" "B.Mask" "B.Paste")
			(net "SW_P12V_P0V8_PEX1_FLT")
		)
		(pad "2" smd rect
			(at -0.889 0 270)
			(size 1.016 1.27)
			(layers "B.Cu" "B.Mask" "B.Paste")
			(net "GND")
		)
	)
	(footprint ""
		(layer "B.Cu")
		(at 405.145748 -296.37482)
		(property "Reference" "C1875"
			(at 0 0 0)
			(layer "B.SilkS")
			(hide yes)
			(effects
				(font
					(size 1.27 1.27)
				)
				(justify mirror)
			)
		)
		(property "Value" ""
			(at 0 0 0)
			(layer "B.Fab")
			(effects
				(font
					(size 1.27 1.27)
				)
				(justify mirror)
			)
		)
		(duplicate_pad_numbers_are_jumpers no)
		(fp_line
			(start -0.299974 -0.150114)
			(end -0.299974 0.150114)
			(stroke
				(width 0.1)
				(type default)
			)
			(layer "B.Fab")
		)
		(fp_line
			(start -0.299974 0.150114)
			(end 0.299974 0.150114)
			(stroke
				(width 0.1)
				(type default)
			)
			(layer "B.Fab")
		)
		(fp_line
			(start 0.299974 -0.150114)
			(end -0.299974 -0.150114)
			(stroke
				(width 0.1)
				(type default)
			)
			(layer "B.Fab")
		)
		(fp_line
			(start 0.299974 0.150114)
			(end 0.299974 -0.150114)
			(stroke
				(width 0.1)
				(type default)
			)
			(layer "B.Fab")
		)
		(pad "1" smd rect
			(at 0.2667 0 180)
			(size 0.3048 0.381)
			(layers "B.Cu" "B.Mask" "B.Paste")
			(net "P0V8_PEX3")
		)
		(pad "2" smd rect
			(at -0.2667 0 180)
			(size 0.3048 0.381)
			(layers "B.Cu" "B.Mask" "B.Paste")
			(net "GND")
		)
	)
	(footprint ""
		(layer "B.Cu")
		(at 109.682788 -285.580328 -90)
		(property "Reference" "PR7175"
			(at 0 0 90)
			(layer "B.SilkS")
			(hide yes)
			(effects
				(font
					(size 1.27 1.27)
				)
				(justify mirror)
			)
		)
		(property "Value" ""
			(at 0 0 90)
			(layer "B.Fab")
			(effects
				(font
					(size 1.27 1.27)
				)
				(justify mirror)
			)
		)
		(duplicate_pad_numbers_are_jumpers no)
		(fp_line
			(start -0.7874 0.4064)
			(end 0.7874 0.4064)
			(stroke
				(width 0.1524)
				(type default)
			)
			(layer "B.SilkS")
		)
		(fp_line
			(start 0.7874 0.4064)
			(end 0.7874 -0.4064)
			(stroke
				(width 0.1524)
				(type default)
			)
			(layer "B.SilkS")
		)
		(fp_line
			(start -0.7874 -0.4064)
			(end -0.7874 0.4064)
			(stroke
				(width 0.1524)
				(type default)
			)
			(layer "B.SilkS")
		)
		(fp_line
			(start 0.7874 -0.4064)
			(end -0.7874 -0.4064)
			(stroke
				(width 0.1524)
				(type default)
			)
			(layer "B.SilkS")
		)
		(fp_line
			(start -0.67945 0.3048)
			(end -0.120396 0.3048)
			(stroke
				(width 0.1)
				(type default)
			)
			(layer "B.Fab")
		)
		(fp_line
			(start -0.120396 0.3048)
			(end -0.120396 0.2794)
			(stroke
				(width 0.1)
				(type default)
			)
			(layer "B.Fab")
		)
		(fp_line
			(start 0.12065 0.3048)
			(end 0.67945 0.3048)
			(stroke
				(width 0.1)
				(type default)
			)
			(layer "B.Fab")
		)
		(fp_line
			(start 0.67945 0.3048)
			(end 0.67945 -0.305054)
			(stroke
				(width 0.1)
				(type default)
			)
			(layer "B.Fab")
		)
		(fp_line
			(start -0.120396 0.2794)
			(end 0.12065 0.2794)
			(stroke
				(width 0.1)
				(type default)
			)
			(layer "B.Fab")
		)
		(fp_line
			(start 0.12065 0.2794)
			(end 0.12065 0.3048)
			(stroke
				(width 0.1)
				(type default)
			)
			(layer "B.Fab")
		)
		(fp_line
			(start -0.12065 -0.2794)
			(end -0.12065 -0.3048)
			(stroke
				(width 0.1)
				(type default)
			)
			(layer "B.Fab")
		)
		(fp_line
			(start 0.12065 -0.2794)
			(end -0.12065 -0.2794)
			(stroke
				(width 0.1)
				(type default)
			)
			(layer "B.Fab")
		)
		(fp_line
			(start -0.67945 -0.3048)
			(end -0.67945 0.3048)
			(stroke
				(width 0.1)
				(type default)
			)
			(layer "B.Fab")
		)
		(fp_line
			(start -0.12065 -0.3048)
			(end -0.67945 -0.3048)
			(stroke
				(width 0.1)
				(type default)
			)
			(layer "B.Fab")
		)
		(fp_line
			(start 0.12065 -0.305054)
			(end 0.12065 -0.2794)
			(stroke
				(width 0.1)
				(type default)
			)
			(layer "B.Fab")
		)
		(fp_line
			(start 0.67945 -0.305054)
			(end 0.12065 -0.305054)
			(stroke
				(width 0.1)
				(type default)
			)
			(layer "B.Fab")
		)
		(pad "1" smd circle
			(at 0.40005 0 90)
			(size 0 0)
			(layers "B.Cu" "B.Mask" "B.Paste")
			(net "P0V8_PEX0_PVCC")
		)
		(pad "2" smd circle
			(at -0.40005 0 90)
			(size 0 0)
			(layers "B.Cu" "B.Mask" "B.Paste")
			(net "P5V_AUX")
		)
	)
	(footprint ""
		(layer "B.Cu")
		(at 407.949908 -299.699934 -90)
		(property "Reference" "C1976"
			(at 0 0 90)
			(layer "B.SilkS")
			(hide yes)
			(effects
				(font
					(size 1.27 1.27)
				)
				(justify mirror)
			)
		)
		(property "Value" ""
			(at 0 0 90)
			(layer "B.Fab")
			(effects
				(font
					(size 1.27 1.27)
				)
				(justify mirror)
			)
		)
		(duplicate_pad_numbers_are_jumpers no)
		(fp_line
			(start -0.299974 0.150114)
			(end 0.299974 0.150114)
			(stroke
				(width 0.1)
				(type default)
			)
			(layer "B.Fab")
		)
		(fp_line
			(start 0.299974 0.150114)
			(end 0.299974 -0.150114)
			(stroke
				(width 0.1)
				(type default)
			)
			(layer "B.Fab")
		)
		(fp_line
			(start -0.299974 -0.150114)
			(end -0.299974 0.150114)
			(stroke
				(width 0.1)
				(type default)
			)
			(layer "B.Fab")
		)
		(fp_line
			(start 0.299974 -0.150114)
			(end -0.299974 -0.150114)
			(stroke
				(width 0.1)
				(type default)
			)
			(layer "B.Fab")
		)
		(pad "1" smd rect
			(at 0.2667 0 90)
			(size 0.3048 0.381)
			(layers "B.Cu" "B.Mask" "B.Paste")
			(net "P0V8_SERDES_VDDA_PEX3")
		)
		(pad "2" smd rect
			(at -0.2667 0 90)
			(size 0.3048 0.381)
			(layers "B.Cu" "B.Mask" "B.Paste")
			(net "GND")
		)
	)
	(footprint ""
		(layer "B.Cu")
		(at 219.301314 -98.61423 180)
		(property "Reference" "R5621"
			(at 0 0 0)
			(layer "B.SilkS")
			(hide yes)
			(effects
				(font
					(size 1.27 1.27)
				)
				(justify mirror)
			)
		)
		(property "Value" ""
			(at 0 0 0)
			(layer "B.Fab")
			(effects
				(font
					(size 1.27 1.27)
				)
				(justify mirror)
			)
		)
		(duplicate_pad_numbers_are_jumpers no)
		(fp_line
			(start 0.7874 0.4064)
			(end 0.7874 -0.4064)
			(stroke
				(width 0.1524)
				(type default)
			)
			(layer "B.SilkS")
		)
		(fp_line
			(start 0.7874 -0.4064)
			(end -0.7874 -0.4064)
			(stroke
				(width 0.1524)
				(type default)
			)
			(layer "B.SilkS")
		)
		(fp_line
			(start -0.7874 0.4064)
			(end 0.7874 0.4064)
			(stroke
				(width 0.1524)
				(type default)
			)
			(layer "B.SilkS")
		)
		(fp_line
			(start -0.7874 -0.4064)
			(end -0.7874 0.4064)
			(stroke
				(width 0.1524)
				(type default)
			)
			(layer "B.SilkS")
		)
		(fp_line
			(start 0.67945 0.3048)
			(end 0.67945 -0.305054)
			(stroke
				(width 0.1)
				(type default)
			)
			(layer "B.Fab")
		)
		(fp_line
			(start 0.67945 -0.305054)
			(end 0.12065 -0.305054)
			(stroke
				(width 0.1)
				(type default)
			)
			(layer "B.Fab")
		)
		(fp_line
			(start 0.12065 0.3048)
			(end 0.67945 0.3048)
			(stroke
				(width 0.1)
				(type default)
			)
			(layer "B.Fab")
		)
		(fp_line
			(start 0.12065 0.2794)
			(end 0.12065 0.3048)
			(stroke
				(width 0.1)
				(type default)
			)
			(layer "B.Fab")
		)
		(fp_line
			(start 0.12065 -0.2794)
			(end -0.12065 -0.2794)
			(stroke
				(width 0.1)
				(type default)
			)
			(layer "B.Fab")
		)
		(fp_line
			(start 0.12065 -0.305054)
			(end 0.12065 -0.2794)
			(stroke
				(width 0.1)
				(type default)
			)
			(layer "B.Fab")
		)
		(fp_line
			(start -0.120396 0.3048)
			(end -0.120396 0.2794)
			(stroke
				(width 0.1)
				(type default)
			)
			(layer "B.Fab")
		)
		(fp_line
			(start -0.120396 0.2794)
			(end 0.12065 0.2794)
			(stroke
				(width 0.1)
				(type default)
			)
			(layer "B.Fab")
		)
		(fp_line
			(start -0.12065 -0.2794)
			(end -0.12065 -0.3048)
			(stroke
				(width 0.1)
				(type default)
			)
			(layer "B.Fab")
		)
		(fp_line
			(start -0.12065 -0.3048)
			(end -0.67945 -0.3048)
			(stroke
				(width 0.1)
				(type default)
			)
			(layer "B.Fab")
		)
		(fp_line
			(start -0.67945 0.3048)
			(end -0.120396 0.3048)
			(stroke
				(width 0.1)
				(type default)
			)
			(layer "B.Fab")
		)
		(fp_line
			(start -0.67945 -0.3048)
			(end -0.67945 0.3048)
			(stroke
				(width 0.1)
				(type default)
			)
			(layer "B.Fab")
		)
		(pad "1" smd circle
			(at 0.40005 0)
			(size 0 0)
			(layers "B.Cu" "B.Mask" "B.Paste")
			(net "NIC3_ADC_A0")
		)
		(pad "2" smd circle
			(at -0.40005 0)
			(size 0 0)
			(layers "B.Cu" "B.Mask" "B.Paste")
			(net "SMB_NIC3_ADC_SCL")
		)
	)
	(footprint ""
		(layer "B.Cu")
		(at 173.850046 -299.699934 -90)
		(property "Reference" "C1463"
			(at 0 0 90)
			(layer "B.SilkS")
			(hide yes)
			(effects
				(font
					(size 1.27 1.27)
				)
				(justify mirror)
			)
		)
		(property "Value" ""
			(at 0 0 90)
			(layer "B.Fab")
			(effects
				(font
					(size 1.27 1.27)
				)
				(justify mirror)
			)
		)
		(duplicate_pad_numbers_are_jumpers no)
		(fp_line
			(start -0.299974 0.150114)
			(end 0.299974 0.150114)
			(stroke
				(width 0.1)
				(type default)
			)
			(layer "B.Fab")
		)
		(fp_line
			(start 0.299974 0.150114)
			(end 0.299974 -0.150114)
			(stroke
				(width 0.1)
				(type default)
			)
			(layer "B.Fab")
		)
		(fp_line
			(start -0.299974 -0.150114)
			(end -0.299974 0.150114)
			(stroke
				(width 0.1)
				(type default)
			)
			(layer "B.Fab")
		)
		(fp_line
			(start 0.299974 -0.150114)
			(end -0.299974 -0.150114)
			(stroke
				(width 0.1)
				(type default)
			)
			(layer "B.Fab")
		)
		(pad "1" smd rect
			(at 0.2667 0 90)
			(size 0.3048 0.381)
			(layers "B.Cu" "B.Mask" "B.Paste")
			(net "P0V8_SERDES_VDDA_PEX1")
		)
		(pad "2" smd rect
			(at -0.2667 0 90)
			(size 0.3048 0.381)
			(layers "B.Cu" "B.Mask" "B.Paste")
			(net "GND")
		)
	)
)
